# S9S_MB_2U (Grand Teton) — schematic netlist excerpt (pin names and nets, part order shuffled) for the footprints in the layout excerpt that follows; sources: Cadence DE-HDL packaged netlist, KiCad conversion of 03242023_DA0F0TMBIJ0_F0T_Motherboard_J_brd_V01_OCP.brd

C2021  Q_CAP  0.1UF 25V 10% X7R  pkg 0402  page 172 : A = VSENSE_P12V_INA230_4_INP ; B = VSENSE_P12V_INA230_4_INN
PC1347  Q_CAP  0.1UF 25V 10% X7R  pkg 0402  page 275 : A = GND ; B = PVCCINFAON_CPU0_VREF

(kicad_pcb
	(version 20260206)
	(generator "pcbnew")
	(generator_version "10.0")
	(general
		(thickness 1.6)
		(legacy_teardrops no)
	)
	(paper "A4")
	(title_block
		(title "03242023_DA0F0TMBIJ0_F0T_Motherboard_J_brd_V01_OCP.brd")
		(comment 1 "Grand Teton / footprints 1239-1240 of 6105")
	)
	(layers
		(0 "F.Cu" signal "TOP")
		(4 "In1.Cu" signal "GND")
		(6 "In2.Cu" signal "IN1")
		(8 "In3.Cu" signal "GND1")
		(10 "In4.Cu" signal "IN2")
		(12 "In5.Cu" signal "GND2")
		(14 "In6.Cu" signal "IN3")
		(16 "In7.Cu" signal "GND3")
		(18 "In8.Cu" signal "VCC")
		(20 "In9.Cu" signal "VCC1")
		(22 "In10.Cu" signal "GND4")
		(24 "In11.Cu" signal "IN4")
		(26 "In12.Cu" signal "GND5")
		(28 "In13.Cu" signal "IN5")
		(30 "In14.Cu" signal "GND6")
		(32 "In15.Cu" signal "IN6")
		(34 "In16.Cu" signal "GND7")
		(2 "B.Cu" signal "BOTTOM")
		(9 "F.Adhes" user "F.Adhesive")
		(11 "B.Adhes" user "B.Adhesive")
		(13 "F.Paste" user "Package Geometry/Pastemask Top")
		(15 "B.Paste" user "Package Geometry/Pastemask Bottom")
		(5 "F.SilkS" user "Ref Des/Silkscreen Top")
		(7 "B.SilkS" user "Ref Des/Silkscreen Bottom")
		(1 "F.Mask" user "Board Geometry/Soldermask Top")
		(3 "B.Mask" user "Board Geometry/Soldermask Bottom")
		(17 "Dwgs.User" user "User.Drawings")
		(19 "Cmts.User" user "User.Comments")
		(21 "Eco1.User" user "User.Eco1")
		(23 "Eco2.User" user "User.Eco2")
		(25 "Edge.Cuts" user "Board Geometry/Outline")
		(27 "Margin" user)
		(31 "F.CrtYd" user "Package Geometry/Place Bound Top")
		(29 "B.CrtYd" user "Package Geometry/Place Bound Bottom")
		(35 "F.Fab" user "Ref Des/Assembly Top")
		(33 "B.Fab" user "Ref Des/Assembly Bottom")
	)
	(footprint ""
		(layer "F.Cu")
		(at 157.870144 -53.359304 -90)
		(property "Reference" "C2021"
			(at 0 0 270)
			(layer "F.SilkS")
			(hide yes)
			(effects
				(font
					(size 1.27 1.27)
				)
			)
		)
		(property "Value" ""
			(at 0 0 270)
			(layer "F.Fab")
			(effects
				(font
					(size 1.27 1.27)
				)
			)
		)
		(duplicate_pad_numbers_are_jumpers no)
		(fp_line
			(start -0.7874 0.4064)
			(end -0.7874 -0.4064)
			(stroke
				(width 0.1524)
				(type default)
			)
			(layer "F.SilkS")
		)
		(fp_line
			(start 0.7874 0.4064)
			(end -0.7874 0.4064)
			(stroke
				(width 0.1524)
				(type default)
			)
			(layer "F.SilkS")
		)
		(fp_line
			(start -0.7874 -0.4064)
			(end 0.7874 -0.4064)
			(stroke
				(width 0.1524)
				(type default)
			)
			(layer "F.SilkS")
		)
		(fp_line
			(start 0.7874 -0.4064)
			(end 0.7874 0.4064)
			(stroke
				(width 0.1524)
				(type default)
			)
			(layer "F.SilkS")
		)
		(fp_line
			(start -0.67945 0.3048)
			(end -0.67945 -0.305054)
			(stroke
				(width 0.1)
				(type default)
			)
			(layer "F.Fab")
		)
		(fp_line
			(start -0.12065 0.3048)
			(end -0.67945 0.3048)
			(stroke
				(width 0.1)
				(type default)
			)
			(layer "F.Fab")
		)
		(fp_line
			(start 0.120396 0.3048)
			(end 0.120396 0.2794)
			(stroke
				(width 0.1)
				(type default)
			)
			(layer "F.Fab")
		)
		(fp_line
			(start 0.67945 0.3048)
			(end 0.120396 0.3048)
			(stroke
				(width 0.1)
				(type default)
			)
			(layer "F.Fab")
		)
		(fp_line
			(start -0.12065 0.2794)
			(end -0.12065 0.3048)
			(stroke
				(width 0.1)
				(type default)
			)
			(layer "F.Fab")
		)
		(fp_line
			(start 0.120396 0.2794)
			(end -0.12065 0.2794)
			(stroke
				(width 0.1)
				(type default)
			)
			(layer "F.Fab")
		)
		(fp_line
			(start -0.12065 -0.2794)
			(end 0.12065 -0.2794)
			(stroke
				(width 0.1)
				(type default)
			)
			(layer "F.Fab")
		)
		(fp_line
			(start 0.12065 -0.2794)
			(end 0.12065 -0.3048)
			(stroke
				(width 0.1)
				(type default)
			)
			(layer "F.Fab")
		)
		(fp_line
			(start 0.12065 -0.3048)
			(end 0.67945 -0.3048)
			(stroke
				(width 0.1)
				(type default)
			)
			(layer "F.Fab")
		)
		(fp_line
			(start 0.67945 -0.3048)
			(end 0.67945 0.3048)
			(stroke
				(width 0.1)
				(type default)
			)
			(layer "F.Fab")
		)
		(fp_line
			(start -0.67945 -0.305054)
			(end -0.12065 -0.305054)
			(stroke
				(width 0.1)
				(type default)
			)
			(layer "F.Fab")
		)
		(fp_line
			(start -0.12065 -0.305054)
			(end -0.12065 -0.2794)
			(stroke
				(width 0.1)
				(type default)
			)
			(layer "F.Fab")
		)
		(pad "1" smd circle
			(at -0.40005 0 270)
			(size 0 0)
			(layers "F.Cu" "F.Mask" "F.Paste")
			(net "VSENSE_P12V_INA230_4_INP")
		)
		(pad "2" smd circle
			(at 0.40005 0 270)
			(size 0 0)
			(layers "F.Cu" "F.Mask" "F.Paste")
			(net "VSENSE_P12V_INA230_4_INN")
		)
	)
	(footprint ""
		(layer "F.Cu")
		(at 420.591488 -173.654974 180)
		(property "Reference" "PC1347"
			(at 0 0 180)
			(layer "F.SilkS")
			(hide yes)
			(effects
				(font
					(size 1.27 1.27)
				)
			)
		)
		(property "Value" ""
			(at 0 0 180)
			(layer "F.Fab")
			(effects
				(font
					(size 1.27 1.27)
				)
			)
		)
		(duplicate_pad_numbers_are_jumpers no)
		(fp_line
			(start 0.7874 0.4064)
			(end -0.7874 0.4064)
			(stroke
				(width 0.1524)
				(type default)
			)
			(layer "F.SilkS")
		)
		(fp_line
			(start 0.7874 -0.4064)
			(end 0.7874 0.4064)
			(stroke
				(width 0.1524)
				(type default)
			)
			(layer "F.SilkS")
		)
		(fp_line
			(start -0.7874 0.4064)
			(end -0.7874 -0.4064)
			(stroke
				(width 0.1524)
				(type default)
			)
			(layer "F.SilkS")
		)
		(fp_line
			(start -0.7874 -0.4064)
			(end 0.7874 -0.4064)
			(stroke
				(width 0.1524)
				(type default)
			)
			(layer "F.SilkS")
		)
		(fp_line
			(start 0.67945 0.3048)
			(end 0.120396 0.3048)
			(stroke
				(width 0.1)
				(type default)
			)
			(layer "F.Fab")
		)
		(fp_line
			(start 0.67945 -0.3048)
			(end 0.67945 0.3048)
			(stroke
				(width 0.1)
				(type default)
			)
			(layer "F.Fab")
		)
		(fp_line
			(start 0.12065 -0.2794)
			(end 0.12065 -0.3048)
			(stroke
				(width 0.1)
				(type default)
			)
			(layer "F.Fab")
		)
		(fp_line
			(start 0.12065 -0.3048)
			(end 0.67945 -0.3048)
			(stroke
				(width 0.1)
				(type default)
			)
			(layer "F.Fab")
		)
		(fp_line
			(start 0.120396 0.3048)
			(end 0.120396 0.2794)
			(stroke
				(width 0.1)
				(type default)
			)
			(layer "F.Fab")
		)
		(fp_line
			(start 0.120396 0.2794)
			(end -0.12065 0.2794)
			(stroke
				(width 0.1)
				(type default)
			)
			(layer "F.Fab")
		)
		(fp_line
			(start -0.12065 0.3048)
			(end -0.67945 0.3048)
			(stroke
				(width 0.1)
				(type default)
			)
			(layer "F.Fab")
		)
		(fp_line
			(start -0.12065 0.2794)
			(end -0.12065 0.3048)
			(stroke
				(width 0.1)
				(type default)
			)
			(layer "F.Fab")
		)
		(fp_line
			(start -0.12065 -0.2794)
			(end 0.12065 -0.2794)
			(stroke
				(width 0.1)
				(type default)
			)
			(layer "F.Fab")
		)
		(fp_line
			(start -0.12065 -0.305054)
			(end -0.12065 -0.2794)
			(stroke
				(width 0.1)
				(type default)
			)
			(layer "F.Fab")
		)
		(fp_line
			(start -0.67945 0.3048)
			(end -0.67945 -0.305054)
			(stroke
				(width 0.1)
				(type default)
			)
			(layer "F.Fab")
		)
		(fp_line
			(start -0.67945 -0.305054)
			(end -0.12065 -0.305054)
			(stroke
				(width 0.1)
				(type default)
			)
			(layer "F.Fab")
		)
		(pad "1" smd circle
			(at -0.40005 0 180)
			(size 0 0)
			(layers "F.Cu" "F.Mask" "F.Paste")
			(net "GND")
		)
		(pad "2" smd circle
			(at 0.40005 0 180)
			(size 0 0)
			(layers "F.Cu" "F.Mask" "F.Paste")
			(net "PVCCINFAON_CPU0_VREF")
		)
	)
)
